# BASEBOARD_FAB2 (Tioga Pass) — schematic parts with pin connectivity, parts 489–648 of 4751; source: Cadence DE-HDL packaged netlist (pstxprt.dat, pstxnet.dat, pstchip.dat)

C2T27  CAP_A  0.01UF 25V 10% X7R  pkg 0402V  page 101 : 1 = P3V3_STBY_MNG_RGMII ; 2 = GND
C2T28  CAP_A  1.0UF 6.3V 10% X6S  pkg 0402V  page 101 : 1 = P3V3_STBY ; 2 = GND
C2T29  CAP_A  0.1UF 16V 10% X7R  pkg 0402V  page 185 : 1 = P3V3 ; 2 = GND
C2T30  CAP_A  0.1UF 16V 10% X7R  pkg 0402V  page 101 : 1 = P3V3_STBY_MNG ; 2 = GND
C2T31  CAP_A  1.0UF 6.3V 10% X6S  pkg 0402V  page 101 : 1 = P3V3_STBY_MNG_RGMII ; 2 = GND
C2T32  CAP_A  0.1UF 16V 10% X7R  pkg 0402V  page 93 : 1 = P0V7_GTL2104_5_VREF ; 2 = GND
C2T33  CAP_A  1.0UF 6.3V 10% X6S  pkg 0402V  page 93 : 1 = P3V3 ; 2 = GND
C2T34  CAP_A  0.1UF 16V 10% X7R  pkg 0402V  page 101 : 1 = P3V3_STBY_MNG ; 2 = GND
C2T35  CAP_A  0.1UF 16V 10% X7R  pkg 0402V  page 156 : 1 = P3V3_STBY ; 2 = GND
C2T36  CAP_A  0.1UF 16V 10% X7R  pkg 0402V  page 198 : 1 = P3V3_STBY ; 2 = GND
C2T37  CAP_A  0.01UF 25V 10% X7R  pkg 0402V  page 101 : 1 = P3V3_STBY_MNG_RMII ; 2 = GND
C2T38  CAP_A  1.0UF 6.3V 10% X6S  pkg 0402V  page 101 : 1 = P3V3_STBY_MNG_RMII ; 2 = GND
C2U1  CAP  10UF 16V 10% X6S  pkg 0805  page 198 : 1 = P3V3_STBY ; 2 = GND
C2U2  CAP  10UF 16V 10% X6S  pkg 0805  page 198 : 1 = P3V3 ; 2 = GND
C2U3  CAP  0.22UF 16V 10% X7R  pkg 0402  page 107 : 1 = P3E_CPU0_PE1_PCH_RXP<0> ; 2 = P3E_CPU0_PE1_SS_RXP<0>
C2U4  CAP  0.22UF 16V 10% X7R  pkg 0402  page 107 : 1 = P3E_CPU0_PE1_PCH_RXN<0> ; 2 = P3E_CPU0_PE1_SS_RXN<0>
C2U5  CAP  0.22UF 16V 10% X7R  pkg 0402  page 107 : 1 = P3E_CPU0_PE1_PCH_RXP<1> ; 2 = P3E_CPU0_PE1_SS_RXP<1>
C2U6  CAP  0.22UF 16V 10% X7R  pkg 0402  page 107 : 1 = P3E_CPU0_PE1_PCH_RXN<1> ; 2 = P3E_CPU0_PE1_SS_RXN<1>
C2U7  CAP  0.22UF 16V 10% X7R  pkg 0402  page 107 : 1 = P3E_CPU0_PE1_PCH_RXP<2> ; 2 = P3E_CPU0_PE1_SS_RXP<2>
C2U8  CAP  0.22UF 16V 10% X7R  pkg 0402  page 107 : 1 = P3E_CPU0_PE1_PCH_RXN<2> ; 2 = P3E_CPU0_PE1_SS_RXN<2>
C2U9  CAP  0.22UF 16V 10% X7R  pkg 0402  page 107 : 1 = P3E_CPU0_PE1_PCH_RXP<3> ; 2 = P3E_CPU0_PE1_SS_RXP<3>
C2U10  CAP  0.22UF 16V 10% X7R  pkg 0402  page 107 : 1 = P3E_CPU0_PE1_PCH_RXN<3> ; 2 = P3E_CPU0_PE1_SS_RXN<3>
C2U11  CAP  0.22UF 16V 10% X7R  pkg 0402  page 107 : 1 = P3E_CPU0_PE1_PCH_RXP<4> ; 2 = P3E_CPU0_PE1_SS_RXP<4>
C2U12  CAP  0.22UF 16V 10% X7R  pkg 0402  page 107 : 1 = P3E_CPU0_PE1_PCH_RXN<4> ; 2 = P3E_CPU0_PE1_SS_RXN<4>
C2U13  CAP  0.22UF 16V 10% X7R  pkg 0402  page 107 : 1 = P3E_CPU0_PE1_PCH_RXP<5> ; 2 = P3E_CPU0_PE1_SS_RXP<5>
C2U14  CAP  0.22UF 16V 10% X7R  pkg 0402  page 107 : 1 = P3E_CPU0_PE1_PCH_RXN<5> ; 2 = P3E_CPU0_PE1_SS_RXN<5>
C2U15  CAP  0.22UF 16V 10% X7R  pkg 0402  page 107 : 1 = P3E_CPU0_PE1_PCH_RXP<6> ; 2 = P3E_CPU0_PE1_SS_RXP<6>
C2U16  CAP  0.22UF 16V 10% X7R  pkg 0402  page 107 : 1 = P3E_CPU0_PE1_PCH_RXN<6> ; 2 = P3E_CPU0_PE1_SS_RXN<6>
C2U17  CAP  0.22UF 16V 10% X7R  pkg 0402  page 107 : 1 = P3E_CPU0_PE1_PCH_RXP<7> ; 2 = P3E_CPU0_PE1_SS_RXP<7>
C2U18  CAP  0.22UF 16V 10% X7R  pkg 0402  page 107 : 1 = P3E_CPU0_PE1_PCH_RXN<7> ; 2 = P3E_CPU0_PE1_SS_RXN<7>
C2U19  CAP_A  0.1UF 16V 10% X7R  pkg 0402V  page 198 : 1 = P3V3 ; 2 = GND
C2U20  CAP_A  0.1UF 16V 10% X7R  pkg 0402V  page 108 : 1 = P12V ; 2 = GND
C2U21  CAP_A  0.1UF 16V 10% X7R  pkg 0402V  page 108 : 1 = P3V3 ; 2 = GND
C2U22  CAP_A  0.1UF 16V 10% X7R  pkg 0402V  page 108 : 1 = P3V3_STBY ; 2 = GND
C2U23  CAP_A  0.1UF 16V 10% X7R  pkg 0402V  page 108 : 1 = P3V3_STBY ; 2 = GND
C2U24  CAP_A  0.1UF 16V 10% X7R  pkg 0402V  page 108 : 1 = P12V ; 2 = GND
C2U25  CAP_A  0.1UF 16V 10% X7R  pkg 0402V  page 108 : 1 = P3V3 ; 2 = GND
C2U26  CAP_A  1.0UF 6.3V 10% X6S  pkg 0402V  page 196 : 1 = P3V3_RTC_STBY ; 2 = GND
C2U27  CAP_A  0.1UF 16V 10% X7R  pkg 0402V  page 161 : 1 = P3V3_STBY ; 2 = GND
C2U28  CAP_A  0.1UF 16V 10% X7R  pkg 0402V  page 161 : 1 = P3V3_STBY ; 2 = GND
C3A1  CAP_A  47UF 4V 20% X5R  pkg 0603V  page 228 : 1 = PVDDQ_KLM ; 2 = GND
C3A2  CAP_A  47UF 4V 20% X5R  pkg 0603V  page 228 : 1 = PVDDQ_KLM ; 2 = GND
C3A3  CAP  10UF 4V 20% X6S  pkg 0603LF  page 234 : 1 = PVPP_KLM ; 2 = GND
C3A4  CAP  10UF 4V 20% X6S  pkg 0603LF  page 234 : 1 = PVPP_KLM ; 2 = GND
C3A5  CAP_A  47UF 4V 20% X5R  pkg 0603V  page 228 : 1 = PVDDQ_KLM ; 2 = GND
C3A6  CAP_A  47UF 4V 20% X5R  pkg 0603V  page 228 : 1 = PVDDQ_KLM ; 2 = GND
C3A7  CAP  10UF 4V 20% X6S  pkg 0603LF  page 234 : 1 = PVPP_KLM ; 2 = GND
C3A8  CAP  10UF 4V 20% X6S  pkg 0603LF  page 234 : 1 = PVPP_KLM ; 2 = GND
C3B1  CAP  10UF 4V 20% X6S  pkg 0603LF  page 234 : 1 = PVPP_KLM ; 2 = GND
C3B2  CAP  10UF 4V 20% X6S  pkg 0603LF  page 234 : 1 = PVPP_KLM ; 2 = GND
C3B3  CAPP  330UF 6.3V 20% POSCAP  pkg 7343LF  page 234 : 1 = PVPP_KLM ; 2 = GND
C3B4  CAP_A  0.1UF 16V 10% X7R  pkg 0402V  page 99 : 1 = PVCCIO_CPU1 ; 2 = GND
C3B5  CAP_A  0.1UF 16V 10% X7R  pkg 0402V  page 99 : 1 = PVPP_KLM ; 2 = GND
C3B6  CAPP  68UF 16V 20% TANT  pkg 3018  page 195 : 1 = P12V_STBY ; 2 = GND
C3C1  CAP_A  1.0UF 6.3V 10% X6S  pkg 0402V  page 193 : 1 = PVCCIOMCP_CPU1 ; 2 = GND
C3C2  CAP_A  1.0UF 6.3V 10% X6S  pkg 0402V  page 193 : 1 = PVCCIOMCP_CPU1 ; 2 = GND
C3D1  CAP_A  22.0UF 4V 20% X6S  pkg 0603V  page 228 : 1 = PVDDQ_KLM ; 2 = GND
C3D2  CAP_A  22.0UF 4V 20% X6S  pkg 0603V  page 76 : 1 = PVCCIN_CPU1 ; 2 = GND
C3D3  CAP  10UF 4V 20% X6S  pkg 0603LF  page 72 : 1 = P1V8_MCP_CPU1 ; 2 = GND
C3D4  CAP_A  22.0UF 4V 20% X6S  pkg 0603V  page 76 : 1 = PVCCMCP_CPU1 ; 2 = GND
C3D5  CAP_A  22.0UF 4V 20% X6S  pkg 0603V  page 76 : 1 = PVCCMCP_CPU1 ; 2 = GND
C3D6  CAP_A  22.0UF 4V 20% X6S  pkg 0603V  page 76 : 1 = PVCCMCP_CPU1 ; 2 = GND
C3D7  CAP_A  22.0UF 4V 20% X6S  pkg 0603V  page 76 : 1 = PVCCMCP_CPU1 ; 2 = GND
C3D8  CAP_A  22.0UF 4V 20% X6S  pkg 0603V  page 76 : 1 = PVCCIO_CPU1 ; 2 = GND
C3D9  CAP_A  22.0UF 4V 20% X6S  pkg 0603V  page 76 : 1 = PVCCIO_CPU1 ; 2 = GND
C3D10  CAP_A  22.0UF 4V 20% X6S  pkg 0603V  page 76 : 1 = PVCCMCP_CPU1 ; 2 = GND
C3D11  CAP_A  22.0UF 4V 20% X6S  pkg 0603V  page 76 : 1 = PVCCMCP_CPU1 ; 2 = GND
C3D12  CAP_A  22.0UF 4V 20% X6S  pkg 0603V  page 76 : 1 = PVCCMCP_CPU1 ; 2 = GND
C3D13  CAP_A  22.0UF 4V 20% X6S  pkg 0603V  page 76 : 1 = PVCCMCP_CPU1 ; 2 = GND
C3D14  CAP_A  22.0UF 4V 20% X6S  pkg 0603V  page 76 : 1 = PVCCMCP_CPU1 ; 2 = GND
C3D15  CAP_A  22.0UF 4V 20% X6S  pkg 0603V  page 76 : 1 = PVCCIO_CPU1 ; 2 = GND
C3D16  CAP_A  22.0UF 4V 20% X6S  pkg 0603V  page 76 : 1 = PVCCIO_CPU1 ; 2 = GND
C3D17  CAP_A  22.0UF 4V 20% X6S  pkg 0603V  page 76 : 1 = PVCCMCP_CPU1 ; 2 = GND
C3D18  CAP_A  22.0UF 4V 20% X6S  pkg 0603V  page 76 : 1 = PVCCMCP_CPU1 ; 2 = GND
C3D19  CAP_A  22.0UF 4V 20% X6S  pkg 0603V  page 76 : 1 = PVCCMCP_CPU1 ; 2 = GND
C3D20  CAP_A  22.0UF 4V 20% X6S  pkg 0603V  page 76 : 1 = PVCCMCP_CPU1 ; 2 = GND
C3D21  CAP_A  22.0UF 4V 20% X6S  pkg 0603V  page 76 : 1 = PVCCMCP_CPU1 ; 2 = GND
C3D22  CAP  10UF 16V 10% X7R  pkg 0805  page 102 : 1 = P3V3_DB1200 ; 2 = GND
C3D23  CAP_A  22.0UF 4V 20% X6S  pkg 0603V  page 76 : 1 = PVCCIO_CPU1 ; 2 = GND
C3D24  CAP_A  22.0UF 4V 20% X6S  pkg 0603V  page 76 : 1 = PVCCIO_CPU1 ; 2 = GND
C3D25  CAP_A  22.0UF 4V 20% X6S  pkg 0603V  page 225 : 1 = PVDDQ_GHJ ; 2 = GND
C3D27  CAP_A  0.1UF 16V 10% EMPTY  pkg 0402V  page 214 : 1 = VSENSE_PVCCIO_CPU1_SKT_VSEN ; 2 = VSENSE_PVCCIO_CPU1_SKT_VRTN
C3E1  CAP_A  22.0UF 4V 20% X6S  pkg 0603V  page 214 : 1 = PVCCIO_CPU1 ; 2 = GND
C3F1  CAP_A  47UF 4V 20% X5R  pkg 0603V  page 193 : 1 = P1V8_MCP_CPU1 ; 2 = GND
C3F2  CAP_A  0.1UF 16V 10% X7R  pkg 0402V  page 104 : 1 = P3V3 ; 2 = GND
C3F3  CAP  10UF 4V 20% X6S  pkg 0603LF  page 233 : 1 = PVPP_GHJ ; 2 = GND
C3F4  CAP  10UF 4V 20% X6S  pkg 0603LF  page 233 : 1 = PVPP_GHJ ; 2 = GND
C3G1  CAP_A  47UF 4V 20% X5R  pkg 0603V  page 225 : 1 = PVDDQ_GHJ ; 2 = GND
C3G2  CAP_A  47UF 4V 20% X5R  pkg 0603V  page 225 : 1 = PVDDQ_GHJ ; 2 = GND
C3G3  CAP  10UF 4V 20% X6S  pkg 0603LF  page 233 : 1 = PVPP_GHJ ; 2 = GND
C3G4  CAP  10UF 4V 20% X6S  pkg 0603LF  page 233 : 1 = PVPP_GHJ ; 2 = GND
C3G5  CAP_A  47UF 4V 20% X5R  pkg 0603V  page 225 : 1 = PVDDQ_GHJ ; 2 = GND
C3G6  CAP_A  47UF 4V 20% X5R  pkg 0603V  page 225 : 1 = PVDDQ_GHJ ; 2 = GND
C3G7  CAP  10UF 4V 20% X6S  pkg 0603LF  page 233 : 1 = PVPP_GHJ ; 2 = GND
C3G8  CAP  10UF 4V 20% X6S  pkg 0603LF  page 233 : 1 = PVPP_GHJ ; 2 = GND
C3L1  SC1U10V2KX-4-GP  10%  pkg SMD-BCG6  page 236 : 1 = P5V_STBY ; 2 = GND
C3L2  CAP  10UF 16V 10% X6S  pkg 0805  page 219 : 1 = VR_FET_SW_P12V_STBY_PVDDQ_DEF ; 2 = GND
C3L4  CAP  10UF 16V 10% X6S  pkg 0805  page 219 : 1 = VR_FET_SW_P12V_STBY_PVDDQ_DEF ; 2 = GND
C3L6  CAPP  470UF 2.5V 20% ALUM  pkg 3018  page 220 : 1 = PVDDQ_DEF ; 2 = GND
C3L7  CAP  10UF 16V 10% X6S  pkg 0805  page 236 : 1 = VR_FET_SW_P12V_STBY_PVDDQ_DEF ; 2 = GND
C3L8  CAP  10UF 16V 10% X6S  pkg 0805  page 236 : 1 = VR_FET_SW_P12V_STBY_PVDDQ_DEF ; 2 = GND
C3L9  CAP  10UF 16V 10% X6S  pkg 0805  page 236 : 1 = VR_FET_SW_P12V_STBY_PVDDQ_DEF ; 2 = GND
C3L10  CAP  10UF 16V 10% X6S  pkg 0805  page 236 : 1 = VR_FET_SW_P12V_STBY_PVDDQ_DEF ; 2 = GND
C3L11  CAP  10UF 16V 10% X6S  pkg 0805  page 236 : 1 = VR_FET_SW_P12V_STBY_PVDDQ_DEF ; 2 = GND
C3L12  CAP  10UF 16V 10% X6S  pkg 0805  page 236 : 1 = VR_FET_SW_P12V_STBY_PVDDQ_DEF ; 2 = GND
C3L13  CAP  10UF 16V 10% X6S  pkg 0805  page 219 : 1 = VR_FET_SW_P12V_STBY_PVDDQ_DEF ; 2 = GND
C3L14  CAPP  470UF 2.5V 20% ALUM  pkg 3018  page 220 : 1 = PVDDQ_DEF ; 2 = GND
C3L15  CAP  10UF 16V 10% X6S  pkg 0805  page 219 : 1 = VR_FET_SW_P12V_STBY_PVDDQ_DEF ; 2 = GND
C3L16  CAP  10UF 16V 10% X6S  pkg 0805  page 219 : 1 = VR_FET_SW_P12V_STBY_PVDDQ_DEF ; 2 = GND
C3L17  CAP  10UF 16V 10% X6S  pkg 0805  page 219 : 1 = VR_FET_SW_P12V_STBY_PVDDQ_DEF ; 2 = GND
C3L18  CAPP  470UF 2V 20% ALUM  pkg SM  page 236 : 1 = PVNN_PCH_STBY ; 2 = GND
C3L19  CAPP  470UF 2V 20% ALUM  pkg SM  page 236 : 1 = P1V05_PCH_STBY ; 2 = GND
C3L20  CAPP  470UF 2V 20% ALUM  pkg SM  page 236 : 1 = PVNN_PCH_STBY ; 2 = GND
C3L21  CAPP  470UF 2V 20% ALUM  pkg SM  page 236 : 1 = PVNN_PCH_STBY ; 2 = GND
C3L22  CAP_A  22.0UF 4V 20% X6S  pkg 0603V  page 132 : 1 = PVNN_PCH_STBY ; 2 = GND
C3L23  CAP_A  22.0UF 4V 20% X6S  pkg 0603V  page 132 : 1 = PVNN_PCH_STBY ; 2 = GND
C3L24  CAP_A  22.0UF 4V 20% X6S  pkg 0603V  page 132 : 1 = PVNN_PCH_STBY ; 2 = GND
C3L25  CAP_A  22.0UF 4V 20% X6S  pkg 0603V  page 132 : 1 = PVNN_PCH_STBY ; 2 = GND
C3L26  CAP_A  22.0UF 4V 20% X6S  pkg 0603V  page 132 : 1 = PVNN_PCH_STBY ; 2 = GND
C3L27  CAP_A  22.0UF 4V 20% X6S  pkg 0603V  page 132 : 1 = PVNN_PCH_STBY ; 2 = GND
C3L29  SC1U10V2KX-4-GP  10%  pkg SMD-BCG6  page 236 : 1 = P5V_STBY ; 2 = GND
C3M1  CAP  0.22UF 16V 10% X7R  pkg 0402  page 105 : 1 = P3E_CPU0_PE1_PCH_R_RXN<15> ; 2 = P3E_CPU0_PE1_PCH_RXN<15>
C3M2  CAP  0.22UF 16V 10% X7R  pkg 0402  page 105 : 1 = P3E_CPU0_PE1_PCH_R_RXP<15> ; 2 = P3E_CPU0_PE1_PCH_RXP<15>
C3M3  CAP  0.22UF 16V 10% X7R  pkg 0402  page 105 : 1 = P3E_CPU0_PE1_PCH_R_RXP<12> ; 2 = P3E_CPU0_PE1_PCH_RXP<12>
C3M4  CAP  0.22UF 16V 10% X7R  pkg 0402  page 105 : 1 = P3E_CPU0_PE1_PCH_R_RXN<12> ; 2 = P3E_CPU0_PE1_PCH_RXN<12>
C3M6  CAP_A  22.0UF 4V 20% X6S  pkg 0603V  page 132 : 1 = PVNN_PCH_STBY ; 2 = GND
C3M7  CAP_A  22.0UF 4V 20% X6S  pkg 0603V  page 132 : 1 = PVNN_PCH_STBY ; 2 = GND
C3M8  CAP  10UF 16V 10% X6S  pkg 0805  page 232 : 1 = VR_FET_SW_P12V_STBY_PVPP_DEF ; 2 = GND
C3M9  CAP  1.0UF 16V 10% X6S  pkg 0402  page 232 : 1 = VR_FET_SW_P12V_STBY_PVPP_DEF ; 2 = GND
C3M10  CAP  4.7UF 6.3V 10% X6S  pkg 0603  page 232 : 1 = VR_VB_PVPP_DEF ; 2 = AGND_PVPP_DEF
C3M11  CAP  0.22UF 16V 10% X7R  pkg 0402  page 105 : 1 = P3E_CPU0_PE1_PCH_R_RXP<14> ; 2 = P3E_CPU0_PE1_PCH_RXP<14>
C3M12  CAP  0.22UF 16V 10% X7R  pkg 0402  page 105 : 1 = P3E_CPU0_PE1_PCH_R_RXN<14> ; 2 = P3E_CPU0_PE1_PCH_RXN<14>
C3M13  CAP  0.22UF 16V 10% X7R  pkg 0402  page 105 : 1 = P3E_CPU0_PE1_PCH_R_RXP<13> ; 2 = P3E_CPU0_PE1_PCH_RXP<13>
C3M14  CAP  0.22UF 16V 10% X7R  pkg 0402  page 105 : 1 = P3E_CPU0_PE1_PCH_R_RXN<13> ; 2 = P3E_CPU0_PE1_PCH_RXN<13>
C3M15  CAP  10UF 16V 10% X6S  pkg 0805  page 232 : 1 = VR_FET_SW_P12V_STBY_PVPP_DEF ; 2 = GND
C3M16  CAP  10UF 16V 10% X6S  pkg 0805  page 232 : 1 = VR_FET_SW_P12V_STBY_PVPP_DEF ; 2 = GND
C3M17  CAP  10UF 4V 20% X6S  pkg 0603LF  page 127 : 1 = P1V05_PCH_STBY_VCCA_PLL1 ; 2 = GND
C3M18  CAP  10UF 4V 20% X6S  pkg 0603LF  page 127 : 1 = P1V05_PCH_STBY_VCCA_PLL0 ; 2 = GND
C3M19  CAP_A  1.0UF 6.3V 10% X6S  pkg 0402V  page 127 : 1 = P1V05_PCH_STBY_VCCA_PLL1 ; 2 = GND
C3M20  CAP_A  1.0UF 6.3V 10% X6S  pkg 0402V  page 127 : 1 = P1V05_PCH_STBY_VCCA_PLL0 ; 2 = GND
C3M21  CAP_A  1.0UF 6.3V 10% X6S  pkg 0402V  page 127 : 1 = P1V05_PCH_STBY ; 2 = GND
C3M22  CAP_A  1.0UF 6.3V 10% X6S  pkg 0402V  page 127 : 1 = P1V05_PCH_STBY ; 2 = GND
C3M23  CAP  10UF 4V 20% X6S  pkg 0603LF  page 127 : 1 = P1V05_PCH_STBY_VCCA_XTAL ; 2 = GND
C3M24  CAP  10UF 4V 20% X6S  pkg 0603LF  page 127 : 1 = P1V05_PCH_STBY_ISCLK_PLL ; 2 = GND
C3M25  CAP  0.22UF 16V 10% X7R  pkg 0402  page 105 : 1 = P3E_CPU0_PE1_PCH_R_RXP<11> ; 2 = P3E_CPU0_PE1_PCH_RXP<11>
C3M26  CAP  0.22UF 16V 10% X7R  pkg 0402  page 105 : 1 = P3E_CPU0_PE1_PCH_R_RXN<11> ; 2 = P3E_CPU0_PE1_PCH_RXN<11>
C3M27  CAP_A  1.0UF 6.3V 10% X6S  pkg 0402V  page 127 : 1 = P1V05_PCH_STBY_VCCA_XTAL ; 2 = GND
C3M28  CAP  0.22UF 16V 10% X7R  pkg 0402  page 105 : 1 = P3E_CPU0_PE1_PCH_R_RXP<10> ; 2 = P3E_CPU0_PE1_PCH_RXP<10>
C3M29  CAP_A  1.0UF 6.3V 10% X6S  pkg 0402V  page 127 : 1 = P1V05_PCH_STBY_ISCLK_PLL ; 2 = GND
C3M30  CAP_A  1.0UF 6.3V 10% X6S  pkg 0402V  page 127 : 1 = P1V05_PCH_STBY ; 2 = GND
C3M31  CAP_A  1.0UF 6.3V 10% X6S  pkg 0402V  page 127 : 1 = P1V05_PCH_STBY ; 2 = GND
C3M32  CAP  0.22UF 16V 10% X7R  pkg 0402  page 105 : 1 = P3E_CPU0_PE1_PCH_R_RXN<10> ; 2 = P3E_CPU0_PE1_PCH_RXN<10>
C3M33  CAP  0.22UF 16V 10% X7R  pkg 0402  page 105 : 1 = P3E_CPU0_PE1_PCH_R_RXN<8> ; 2 = P3E_CPU0_PE1_PCH_RXN<8>
C3M34  CAP  0.22UF 16V 10% X7R  pkg 0402  page 105 : 1 = P3E_CPU0_PE1_PCH_R_RXP<8> ; 2 = P3E_CPU0_PE1_PCH_RXP<8>
C3M35  CAP  0.22UF 16V 10% X7R  pkg 0402  page 105 : 1 = P3E_CPU0_PE1_PCH_R_RXN<9> ; 2 = P3E_CPU0_PE1_PCH_RXN<9>
C3M36  CAP  0.22UF 16V 10% X7R  pkg 0402  page 105 : 1 = P3E_CPU0_PE1_PCH_R_RXP<9> ; 2 = P3E_CPU0_PE1_PCH_RXP<9>
C3M37  CAP  0.22UF 16V 10% X7R  pkg 0402  page 129 : 1 = DMI_CPU0_PCH_RX_DP<1> ; 2 = DMI_CPU0_PCH_RX_C_DP<1>
C3M38  CAP_A  1.0UF 6.3V 10% X6S  pkg 0402V  page 131 : 1 = P1V05_PCH_STBY ; 2 = GND
C3M39  CAP_A  1.0UF 6.3V 10% X6S  pkg 0402V  page 131 : 1 = P1V05_PCH_STBY ; 2 = GND
C3M40  CAP  0.22UF 16V 10% X7R  pkg 0402  page 129 : 1 = DMI_CPU0_PCH_RX_DP<0> ; 2 = DMI_CPU0_PCH_RX_C_DP<0>
